# TIMECARD (Time Appliance Project (Time Card)) — schematic netlist excerpt (pin names and nets, part order shuffled) for the footprints in the layout excerpt that follows; sources: Cadence DE-HDL packaged netlist, KiCad conversion of R4006-B0001-02_R01.brd

C145  CAPACITOR  0.1UF 10V 10%  pkg SMC_0402R_H022  page 14 : \1\ = XP3R3V_FPGA ; \2\ = SG
R450  RESISTOR  4.7KOHM 1%  pkg SMC_0402R_H016  page 24 : \1\ = MUX1_SEL ; \2\ = XP3R3V_FPGA

(kicad_pcb
	(version 20260206)
	(generator "pcbnew")
	(generator_version "10.0")
	(general
		(thickness 1.6)
		(legacy_teardrops no)
	)
	(paper "A4")
	(title_block
		(title "timecard-production-celestica-r4006 — R4006-B0001-02_R01.brd")
		(comment 1 "Time Appliance Project (Time Card) / footprints 769-770 of 1113")
	)
	(layers
		(0 "F.Cu" signal "TOP")
		(4 "In1.Cu" signal "L02_GND1")
		(6 "In2.Cu" signal "L03_SIG1")
		(8 "In3.Cu" signal "L04_GND2")
		(10 "In4.Cu" signal "L05_VCC1")
		(12 "In5.Cu" signal "L06_VCC2")
		(14 "In6.Cu" signal "L07_GND3")
		(16 "In7.Cu" signal "L08_SIG2")
		(18 "In8.Cu" signal "L09_GND4")
		(2 "B.Cu" signal "BOTTOM")
		(9 "F.Adhes" user "F.Adhesive")
		(11 "B.Adhes" user "B.Adhesive")
		(13 "F.Paste" user "Package Geometry/Pastemask Top")
		(15 "B.Paste" user "Package Geometry/Pastemask Bottom")
		(5 "F.SilkS" user "Ref Des/Silkscreen Top")
		(7 "B.SilkS" user "Ref Des/Silkscreen Bottom")
		(1 "F.Mask" user "Board Geometry/Soldermask Top")
		(3 "B.Mask" user "Board Geometry/Soldermask Bottom")
		(17 "Dwgs.User" user "User.Drawings")
		(19 "Cmts.User" user "User.Comments")
		(21 "Eco1.User" user "User.Eco1")
		(23 "Eco2.User" user "User.Eco2")
		(25 "Edge.Cuts" user "Board Geometry/Outline")
		(27 "Margin" user)
		(31 "F.CrtYd" user "Package Geometry/Place Bound Top")
		(29 "B.CrtYd" user "Package Geometry/Place Bound Bottom")
		(35 "F.Fab" user "Ref Des/Assembly Top")
		(33 "B.Fab" user "Ref Des/Assembly Bottom")
	)
	(footprint ""
		(layer "B.Cu")
		(at 98.044 -96.774)
		(property "Reference" "R450"
			(at -0.889 -1.61163 0)
			(unlocked yes)
			(layer "B.SilkS")
			(effects
				(font
					(size 0.7874 0.5842)
					(thickness 0.1524)
				)
				(justify mirror)
			)
		)
		(property "Value" "VAL*"
			(at -0.02032 2.13233 0)
			(unlocked yes)
			(layer "B.Fab")
			(hide yes)
			(effects
				(font
					(size 0.7874 0.5842)
					(thickness 0.1524)
				)
				(justify mirror)
			)
		)
		(property "Tolerance" "TOL*"
			(at -0.044704 3.05435 0)
			(unlocked yes)
			(layer "Cmts.User")
			(hide yes)
			(effects
				(font
					(size 0.7874 0.5842)
					(thickness 0.1524)
				)
				(justify mirror)
			)
		)
		(property "User Part Number" "PARTNUM*"
			(at -0.02032 4.024884 0)
			(unlocked yes)
			(layer "Cmts.User")
			(hide yes)
			(effects
				(font
					(size 0.7874 0.5842)
					(thickness 0.1524)
				)
				(justify mirror)
			)
		)
		(property "Device Type" "RESISTOR-G155-14701-01,4.7KOHMA"
			(at -0.008382 1.210564 0)
			(unlocked yes)
			(layer "B.Fab")
			(hide yes)
			(effects
				(font
					(size 0.7874 0.5842)
					(thickness 0.1524)
				)
				(justify mirror)
			)
		)
		(duplicate_pad_numbers_are_jumpers no)
		(fp_line
			(start -1.143 -0.5588)
			(end 1.143 -0.5588)
			(stroke
				(width 0.1)
				(type default)
			)
			(layer "B.SilkS")
		)
		(fp_line
			(start -1.143 0.5588)
			(end -1.143 -0.5588)
			(stroke
				(width 0.1)
				(type default)
			)
			(layer "B.SilkS")
		)
		(fp_line
			(start 1.143 -0.5588)
			(end 1.143 0.5588)
			(stroke
				(width 0.1)
				(type default)
			)
			(layer "B.SilkS")
		)
		(fp_line
			(start 1.143 0.5588)
			(end -1.143 0.5588)
			(stroke
				(width 0.1)
				(type default)
			)
			(layer "B.SilkS")
		)
		(fp_poly
			(pts
				(xy 1.143 0.5588) (xy -1.143 0.5588) (xy -1.143 -0.5588) (xy 1.143 -0.5588)
			)
			(stroke
				(width 0)
				(type default)
			)
			(fill no)
			(layer "B.CrtYd")
		)
		(fp_line
			(start -0.508 -0.3048)
			(end 0.508 -0.3048)
			(stroke
				(width 0.1)
				(type default)
			)
			(layer "B.Fab")
		)
		(fp_line
			(start -0.508 0.3048)
			(end -0.508 -0.3048)
			(stroke
				(width 0.1)
				(type default)
			)
			(layer "B.Fab")
		)
		(fp_line
			(start 0.508 -0.3048)
			(end 0.508 0.3048)
			(stroke
				(width 0.1)
				(type default)
			)
			(layer "B.Fab")
		)
		(fp_line
			(start 0.508 0.3048)
			(end -0.508 0.3048)
			(stroke
				(width 0.1)
				(type default)
			)
			(layer "B.Fab")
		)
		(pad "1" smd rect
			(at 0.5334 0 180)
			(size 0.7112 0.6096)
			(layers "B.Cu" "B.Mask" "B.Paste")
			(net "MUX1_SEL")
		)
		(pad "2" smd rect
			(at -0.5334 0 180)
			(size 0.7112 0.6096)
			(layers "B.Cu" "B.Mask" "B.Paste")
			(net "XP3R3V_FPGA")
		)
		(zone
			(layer "B.Cu")
			(hatch none 0.5)
			(connect_pads
				(clearance 0)
			)
			(min_thickness 0.25)
			(keepout
				(tracks not_allowed)
				(vias allowed)
				(pads allowed)
				(copperpour not_allowed)
				(footprints allowed)
			)
			(placement
				(enabled no)
				(sheetname "")
			)
			(fill
				(thermal_gap 0.5)
				(thermal_bridge_width 0.5)
				(island_removal_mode 0)
			)
			(polygon
				(pts
					(xy 98.1202 -96.4692) (xy 98.1202 -97.0788) (xy 97.9678 -97.0788) (xy 97.9678 -96.4692)
				)
			)
		)
		(zone
			(layer "B.Cu")
			(hatch none 0.5)
			(connect_pads
				(clearance 0)
			)
			(min_thickness 0.25)
			(keepout
				(tracks allowed)
				(vias not_allowed)
				(pads allowed)
				(copperpour not_allowed)
				(footprints allowed)
			)
			(placement
				(enabled no)
				(sheetname "")
			)
			(fill
				(thermal_gap 0.5)
				(thermal_bridge_width 0.5)
				(island_removal_mode 0)
			)
			(polygon
				(pts
					(xy 98.1202 -96.4692) (xy 98.1202 -97.0788) (xy 97.9678 -97.0788) (xy 97.9678 -96.4692)
				)
			)
		)
	)
	(footprint ""
		(layer "B.Cu")
		(at 121.412 -46.789594 90)
		(property "Reference" "C145"
			(at -1.196594 1.49225 270)
			(unlocked yes)
			(layer "B.SilkS")
			(effects
				(font
					(size 0.635 0.4064)
					(thickness 0.1524)
				)
				(justify mirror)
			)
		)
		(property "Value" "VAL*"
			(at -0.0762 2.067306 90)
			(unlocked yes)
			(layer "B.Fab")
			(hide yes)
			(effects
				(font
					(size 0.7874 0.5842)
					(thickness 0.1524)
				)
				(justify mirror)
			)
		)
		(property "Tolerance" "TOL*"
			(at -0.0762 3.032506 90)
			(unlocked yes)
			(layer "Cmts.User")
			(hide yes)
			(effects
				(font
					(size 0.7874 0.5842)
					(thickness 0.1524)
				)
				(justify mirror)
			)
		)
		(property "User Part Number" "PARTNUM*"
			(at -0.1016 4.023106 90)
			(unlocked yes)
			(layer "Cmts.User")
			(hide yes)
			(effects
				(font
					(size 0.7874 0.5842)
					(thickness 0.1524)
				)
				(justify mirror)
			)
		)
		(property "Device Type" "CAPACITOR-G105-0B104-CK,0.1UF,A"
			(at -0.0508 1.127506 90)
			(unlocked yes)
			(layer "B.Fab")
			(hide yes)
			(effects
				(font
					(size 0.7874 0.5842)
					(thickness 0.1524)
				)
				(justify mirror)
			)
		)
		(duplicate_pad_numbers_are_jumpers no)
		(fp_line
			(start 1.143 -0.5588)
			(end 1.143 0.5588)
			(stroke
				(width 0.1)
				(type default)
			)
			(layer "B.SilkS")
		)
		(fp_line
			(start -1.143 -0.5588)
			(end 1.143 -0.5588)
			(stroke
				(width 0.1)
				(type default)
			)
			(layer "B.SilkS")
		)
		(fp_line
			(start 1.143 0.5588)
			(end -1.143 0.5588)
			(stroke
				(width 0.1)
				(type default)
			)
			(layer "B.SilkS")
		)
		(fp_line
			(start -1.143 0.5588)
			(end -1.143 -0.5588)
			(stroke
				(width 0.1)
				(type default)
			)
			(layer "B.SilkS")
		)
		(fp_rect
			(start -1.143 -0.5588)
			(end 1.143 0.5588)
			(stroke
				(width 0)
				(type default)
			)
			(fill no)
			(layer "B.CrtYd")
		)
		(fp_line
			(start 0.508 -0.3048)
			(end 0.508 0.3048)
			(stroke
				(width 0.1)
				(type default)
			)
			(layer "B.Fab")
		)
		(fp_line
			(start -0.508 -0.3048)
			(end 0.508 -0.3048)
			(stroke
				(width 0.1)
				(type default)
			)
			(layer "B.Fab")
		)
		(fp_line
			(start 0.508 0.3048)
			(end -0.508 0.3048)
			(stroke
				(width 0.1)
				(type default)
			)
			(layer "B.Fab")
		)
		(fp_line
			(start -0.508 0.3048)
			(end -0.508 -0.3048)
			(stroke
				(width 0.1)
				(type default)
			)
			(layer "B.Fab")
		)
		(pad "1" smd rect
			(at 0.5334 0 270)
			(size 0.7112 0.6096)
			(layers "B.Cu" "B.Mask" "B.Paste")
			(net "XP3R3V_FPGA")
		)
		(pad "2" smd rect
			(at -0.5334 0 270)
			(size 0.7112 0.6096)
			(layers "B.Cu" "B.Mask" "B.Paste")
			(net "SG")
		)
		(zone
			(layer "B.Cu")
			(hatch none 0.5)
			(connect_pads
				(clearance 0)
			)
			(min_thickness 0.25)
			(keepout
				(tracks allowed)
				(vias not_allowed)
				(pads allowed)
				(copperpour not_allowed)
				(footprints allowed)
			)
			(placement
				(enabled no)
				(sheetname "")
			)
			(fill
				(thermal_gap 0.5)
				(thermal_bridge_width 0.5)
				(island_removal_mode 0)
			)
			(polygon
				(pts
					(xy 121.1072 -46.713394) (xy 121.7168 -46.713394) (xy 121.7168 -46.865794) (xy 121.1072 -46.865794)
				)
			)
		)
	)
)
